# BASEBOARD_FAB2 (Tioga Pass) — schematic netlist excerpt (pin names and nets, part order shuffled) for the footprints in the layout excerpt that follows; sources: Cadence DE-HDL packaged netlist, KiCad conversion of Wiwynn_Tioga_Pass_MB.brd

EU7A5  PXM1310B  IC  pkg QFN  page 218
  BPWM1  = NC
  DNC(0)  = NC
  APWM3  = NC
  APWM2  = VR_PVDDQ_DEF_PWM2
  APWM1  = VR_PVDDQ_DEF_PWM1
  SDA  = SMB_VR_STBY_LVC3_SDA
  SCL  = SMB_VR_STBY_LVC3_SCL
  RESET_N  = NC
  AVRRDY  = PWRGD_PVDDQ_DEF_R
  AVREN  = VR_PVDDQ_DEF_VREN
  VRHOT_N  = IRQ_PVDDQ_DEF_VRHOT_LVT3_R_N
  PINALRT_N  = NC
  MP0  = PU_VR_PVDDQ_DEF_FAULT1
  MP1  = TP_PVDDQ_DEF_MP1
  VCLK  = SVID_CLK_PVDDQ_DEF
  VDIO  = SVID_VDIO_PVDDQ_DEF
  VALRT_N  = SVID_ALERT_PVDDQ_DEF
  MP2  = TP_PVDDQ_DEF_MP2
  AVSEN  = VR_PVDDQ_DEF_AVSP
  AVREF  = VSENSE_PVDDQ_DEF_N
  AIREF1  = VR_PVDDQ_DEF_AIREF1
  AISEN1  = ISENSE_PVDDQ_DEF_PH1_IMON
  AIREF2  = VR_PVDDQ_DEF_AIREF2
  AISEN2  = ISENSE_PVDDQ_DEF_PH2_IMON
  AIREF3  = NC
  AISEN3  = NC
  GND  = GND
  DNC(1)  = NC
  BVSEN  = NC
  BVREF  = NC
  BIREF1  = NC
  BISEN1  = GND
  XADDR2  = VR_PVDDQ_DEF_XADDR2
  BTSEN  = NC
  ATSEN  = A_TSENSE_PVDDQ_DEF
  XADDR1  = VR_PVDDQ_DEF_XADDR1
  VINSEN  = VR_PVDDQ_DEF_VINSEN
  IINSEN  = VR_PVDDQ_DEF_AIINSEN
  VDD  = VR_PVDDQ_DEF_VDD
  VD12  = VR_PVDDQ_DEF_VD12
  THPAD  = GND

(kicad_pcb
	(version 20260206)
	(generator "pcbnew")
	(generator_version "10.0")
	(general
		(thickness 1.6)
		(legacy_teardrops no)
	)
	(paper "A4")
	(title_block
		(title "Wiwynn_Tioga_Pass_MB.brd")
		(comment 1 "Tioga Pass / footprint 1253 of 4770 (EU7A5), pads 35-41 of 41")
	)
	(layers
		(0 "F.Cu" signal "TOP")
		(4 "In1.Cu" signal "L2GND")
		(6 "In2.Cu" signal "L3")
		(8 "In3.Cu" signal "L4GND")
		(10 "In4.Cu" signal "L5")
		(12 "In5.Cu" signal "L6GND")
		(14 "In6.Cu" signal "L7VCC")
		(16 "In7.Cu" signal "L8VCC")
		(18 "In8.Cu" signal "L9GND")
		(20 "In9.Cu" signal "L10")
		(22 "In10.Cu" signal "L11GND")
		(24 "In11.Cu" signal "L12")
		(26 "In12.Cu" signal "L13GND")
		(2 "B.Cu" signal "BOTTOM")
		(9 "F.Adhes" user "F.Adhesive")
		(11 "B.Adhes" user "B.Adhesive")
		(13 "F.Paste" user "Package Geometry/Pastemask Top")
		(15 "B.Paste" user "Package Geometry/Pastemask Bottom")
		(5 "F.SilkS" user "Ref Des/Silkscreen Top")
		(7 "B.SilkS" user "Ref Des/Silkscreen Bottom")
		(1 "F.Mask" user "Board Geometry/Soldermask Top")
		(3 "B.Mask" user "Board Geometry/Soldermask Bottom")
		(17 "Dwgs.User" user "User.Drawings")
		(19 "Cmts.User" user "User.Comments")
		(21 "Eco1.User" user "User.Eco1")
		(23 "Eco2.User" user "User.Eco2")
		(25 "Edge.Cuts" user "Board Geometry/Outline")
		(27 "Margin" user)
		(31 "F.CrtYd" user "Package Geometry/Place Bound Top")
		(29 "B.CrtYd" user "Package Geometry/Place Bound Bottom")
		(35 "F.Fab" user "Ref Des/Assembly Top")
		(33 "B.Fab" user "Ref Des/Assembly Bottom")
	)
	(footprint ""
		(layer "F.Cu")
		(at 359.29824 -138.16457 90)
		(property "Reference" "EU7A5"
			(at -1.51257 -3.29057 90)
			(unlocked yes)
			(layer "F.SilkS")
			(effects
				(font
					(size 0.7874 0.5842)
					(thickness 0.1524)
				)
				(justify left)
			)
		)
		(property "Value" ""
			(at 0 0 90)
			(layer "F.Fab")
			(effects
				(font
					(size 1.27 1.27)
				)
			)
		)
		(duplicate_pad_numbers_are_jumpers no)
		(pad "35" smd custom
			(at 0.199898 -2.4511 90)
			(size 0.0508 0.0508)
			(layers "F.Cu" "F.Mask" "F.Paste")
			(net "A_TSENSE_PVDDQ_DEF")
			(options
				(clearance outline)
				(anchor circle)
			)
			(primitives
				(gr_poly
					(pts
						(arc
							(start 0.1016 0.254)
							(mid 0 0.3556)
							(end -0.1016 0.254)
						)
						(xy -0.1016 -0.3556) (xy 0.1016 -0.3556)
					)
					(width 0)
					(fill yes)
				)
			)
		)
		(pad "36" smd custom
			(at -0.199898 -2.4511 90)
			(size 0.0508 0.0508)
			(layers "F.Cu" "F.Mask" "F.Paste")
			(net "VR_PVDDQ_DEF_XADDR1")
			(options
				(clearance outline)
				(anchor circle)
			)
			(primitives
				(gr_poly
					(pts
						(arc
							(start 0.1016 0.254)
							(mid 0 0.3556)
							(end -0.1016 0.254)
						)
						(xy -0.1016 -0.3556) (xy 0.1016 -0.3556)
					)
					(width 0)
					(fill yes)
				)
			)
		)
		(pad "37" smd custom
			(at -0.599948 -2.4511 90)
			(size 0.0508 0.0508)
			(layers "F.Cu" "F.Mask" "F.Paste")
			(net "VR_PVDDQ_DEF_VINSEN")
			(options
				(clearance outline)
				(anchor circle)
			)
			(primitives
				(gr_poly
					(pts
						(arc
							(start 0.1016 0.254)
							(mid 0 0.3556)
							(end -0.1016 0.254)
						)
						(xy -0.1016 -0.3556) (xy 0.1016 -0.3556)
					)
					(width 0)
					(fill yes)
				)
			)
		)
		(pad "38" smd custom
			(at -0.999998 -2.4511 90)
			(size 0.0508 0.0508)
			(layers "F.Cu" "F.Mask" "F.Paste")
			(net "VR_PVDDQ_DEF_AIINSEN")
			(options
				(clearance outline)
				(anchor circle)
			)
			(primitives
				(gr_poly
					(pts
						(arc
							(start 0.1016 0.254)
							(mid 0 0.3556)
							(end -0.1016 0.254)
						)
						(xy -0.1016 -0.3556) (xy 0.1016 -0.3556)
					)
					(width 0)
					(fill yes)
				)
			)
		)
		(pad "39" smd custom
			(at -1.400048 -2.4511 90)
			(size 0.0508 0.0508)
			(layers "F.Cu" "F.Mask" "F.Paste")
			(net "VR_PVDDQ_DEF_VDD")
			(options
				(clearance outline)
				(anchor circle)
			)
			(primitives
				(gr_poly
					(pts
						(arc
							(start 0.1016 0.254)
							(mid 0 0.3556)
							(end -0.1016 0.254)
						)
						(xy -0.1016 -0.3556) (xy 0.1016 -0.3556)
					)
					(width 0)
					(fill yes)
				)
			)
		)
		(pad "40" smd custom
			(at -1.800098 -2.4511 90)
			(size 0.0508 0.0508)
			(layers "F.Cu" "F.Mask" "F.Paste")
			(net "VR_PVDDQ_DEF_VD12")
			(options
				(clearance outline)
				(anchor circle)
			)
			(primitives
				(gr_poly
					(pts
						(arc
							(start 0.1016 0.254)
							(mid 0 0.3556)
							(end -0.1016 0.254)
						)
						(xy -0.1016 -0.3556) (xy 0.1016 -0.3556)
					)
					(width 0)
					(fill yes)
				)
			)
		)
		(pad "41" smd rect
			(at 0 0 90)
			(size 3.683 3.683)
			(layers "F.Cu" "F.Mask" "F.Paste")
			(net "GND")
		)
	)
)
